FILE_TYPE = CONNECTIVITY;
{Allegro Design Entry HDL 17.2-2016 S081 (4005846) 1/11/2022}
"PAGE_NUMBER" = 98;
0"NC";
1"M_B_CPU1_SA_CB<7:0>";
2"M_B_CPU1_SB_CA<6:0>";
3"M_B_CPU1_SA_CA<6:0>";
4"M_B_CPU1_SB_CB<7:0>";
5"M_B_CPU1_SA_DQ<31:0>";
6"M_B_CPU1_SB_DQ<31:0>";
7"M_B_CPU1_SA_DQS_DN<9:0>";
8"M_B_CPU1_SA_DQS_DP<9:0>";
9"M_B_CPU1_SB_DQS_DN<9:0>";
10"M_B_CPU1_SB_DQS_DP<9:0>";
11"GND\g";
12"GND\g";
13"P3V3_STBY\g";
14"I3C_SPD_DDRAF_CPU1_SCL";
15"I3C_SPD_DDRB_CPU1_SCL";
16"PWRGD_CHB_CPU1_DIMM";
17"TP_CHB_CPU1_DIMM_RFU_5";
18"TP_CHB_CPU1_DIMM_RFU_6";
19"I3C_SPD_DDRAF_CPU1_SDA";
20"PD_CHB_CPU1_DIMM_SAA";
21"P3V3_STBY\g";
22"M_B_CPU1_ALERT_N";
23"TP_CHB_CPU1_DIMM_RFU_2";
24"M_B_CPU1_SA_CA<0>";
25"P12V_MEM_2\g";
26"GND\g";
27"GND\g";
28"GND\g";
29"M_B_CPU1_SA_DQS_DP<7>";
30"M_B_CPU1_SA_DQS_DN<8>";
31"M_B_CPU1_SA_DQ<28>";
32"M_B_CPU1_SA_DQ<19>";
33"M_B_CPU1_SA_DQS_DP<9>";
34"M_B_CPU1_SB_DQS_DP<9>";
35"M_B_CPU1_SB_DQS_DN<9>";
36"M_B_CPU1_SA_DQS_DN<9>";
37"M_B_CPU1_SA_DQS_DP<8>";
38"M_B_CPU1_SB_DQS_DN<7>";
39"M_B_CPU1_SB_DQS_DP<6>";
40"M_B_CPU1_SB_DQS_DN<6>";
41"M_B_CPU1_SA_DQS_DN<6>";
42"M_B_CPU1_SB_DQS_DP<5>";
43"M_B_CPU1_SB_DQS_DN<5>";
44"M_B_CPU1_SA_DQS_DP<5>";
45"M_B_CPU1_SA_DQS_DN<5>";
46"M_B_CPU1_SB_DQS_DP<4>";
47"M_B_CPU1_SB_DQS_DN<4>";
48"M_B_CPU1_SA_DQS_DP<4>";
49"M_B_CPU1_SA_DQS_DN<4>";
50"M_B_CPU1_SB_DQS_DP<3>";
51"M_B_CPU1_SB_DQS_DN<3>";
52"M_B_CPU1_SA_DQS_DP<3>";
53"M_B_CPU1_SA_DQS_DN<3>";
54"M_B_CPU1_SB_DQS_DP<2>";
55"M_B_CPU1_SB_DQS_DN<2>";
56"M_B_CPU1_SA_DQS_DP<2>";
57"M_B_CPU1_SA_DQS_DN<2>";
58"M_B_CPU1_SB_DQS_DP<1>";
59"M_B_CPU1_SB_DQS_DN<1>";
60"M_B_CPU1_SA_DQS_DP<1>";
61"M_B_CPU1_SA_DQS_DN<1>";
62"M_B_CPU1_SB_DQS_DP<0>";
63"M_B_CPU1_SB_DQS_DN<0>";
64"M_B_CPU1_SA_DQS_DP<0>";
65"M_B_CPU1_SA_DQS_DN<0>";
66"M_B_CPU1_SB_DQS_DP<7>";
67"M_B_CPU1_SB_DQS_DN<8>";
68"M_B_CPU1_SB_DQS_DP<8>";
69"M_B_CPU1_SA_DQS_DP<6>";
70"M_B_CPU1_SA_DQS_DN<7>";
71"M_B_CPU1_SA_CA<1>";
72"M_B_CPU1_SA_CA<4>";
73"M_B_CPU1_SA_DQ<31>";
74"M_B_CPU1_SA_DQ<29>";
75"M_B_CPU1_SA_DQ<24>";
76"TP_CHB_CPU1_DIMM_RFU_0";
77"TP_CHB_CPU1_DIMM_RFU_1";
78"TP_CHB_CPU1_DIMM_RFU_3";
79"TP_CHB_CPU1_DIMM_RFU_4";
80"M_B_CPU1_RESET_N";
81"M_B_CPU1_SB_PAR";
82"M_B_CPU1_SA_PAR";
83"M_B_CPU1_SB_RSP<0>";
84"M_B_CPU1_SA_RSP<0>";
85"M_B_CPU1_SB_DQ<0>";
86"M_B_CPU1_SB_DQ<1>";
87"M_B_CPU1_SB_DQ<2>";
88"M_B_CPU1_SB_DQ<3>";
89"M_B_CPU1_SB_DQ<4>";
90"M_B_CPU1_SB_DQ<5>";
91"M_B_CPU1_SB_DQ<6>";
92"M_B_CPU1_SB_DQ<7>";
93"M_B_CPU1_SB_DQ<8>";
94"M_B_CPU1_SB_DQ<9>";
95"M_B_CPU1_SB_DQ<10>";
96"M_B_CPU1_SB_DQ<11>";
97"M_B_CPU1_SB_DQ<12>";
98"M_B_CPU1_SB_DQ<13>";
99"M_B_CPU1_SB_DQ<14>";
100"M_B_CPU1_SB_DQ<15>";
101"M_B_CPU1_SB_DQ<16>";
102"M_B_CPU1_SB_DQ<17>";
103"M_B_CPU1_SB_DQ<18>";
104"M_B_CPU1_SB_DQ<19>";
105"M_B_CPU1_SB_DQ<20>";
106"M_B_CPU1_SB_DQ<21>";
107"M_B_CPU1_SB_DQ<22>";
108"M_B_CPU1_SB_DQ<23>";
109"M_B_CPU1_SB_DQ<24>";
110"M_B_CPU1_SB_DQ<25>";
111"M_B_CPU1_SB_DQ<26>";
112"M_B_CPU1_SB_DQ<27>";
113"M_B_CPU1_SB_DQ<28>";
114"M_B_CPU1_SB_DQ<29>";
115"M_B_CPU1_SB_DQ<30>";
116"M_B_CPU1_SB_DQ<31>";
117"M_B_CPU1_SA_DQ<0>";
118"M_B_CPU1_SA_DQ<1>";
119"M_B_CPU1_SA_DQ<2>";
120"M_B_CPU1_SA_DQ<3>";
121"M_B_CPU1_SA_DQ<4>";
122"M_B_CPU1_SA_DQ<5>";
123"M_B_CPU1_SA_DQ<6>";
124"M_B_CPU1_SA_DQ<7>";
125"M_B_CPU1_SA_DQ<8>";
126"M_B_CPU1_SA_DQ<9>";
127"M_B_CPU1_SA_DQ<10>";
128"M_B_CPU1_SA_DQ<11>";
129"M_B_CPU1_SA_DQ<12>";
130"M_B_CPU1_SA_DQ<13>";
131"M_B_CPU1_SA_DQ<14>";
132"M_B_CPU1_SA_DQ<15>";
133"M_B_CPU1_SA_DQ<16>";
134"M_B_CPU1_SA_DQ<17>";
135"M_B_CPU1_SA_DQ<18>";
136"M_B_CPU1_SA_DQ<20>";
137"M_B_CPU1_SA_DQ<21>";
138"M_B_CPU1_SA_DQ<22>";
139"M_B_CPU1_SA_DQ<23>";
140"M_B_CPU1_SA_DQ<25>";
141"M_B_CPU1_SA_DQ<26>";
142"M_B_CPU1_SA_DQ<27>";
143"M_B_CPU1_SA_DQ<30>";
144"M_B_CPU1_SB_CS_N<1>";
145"M_B_CPU1_SA_CS_N<1>";
146"M_B_CPU1_SB_CS_N<0>";
147"M_B_CPU1_SA_CS_N<0>";
148"M_B_CPU1_CLK_DP<0>";
149"M_B_CPU1_CLK_DN<0>";
150"M_B_CPU1_SB_CB<0>";
151"M_B_CPU1_SB_CB<1>";
152"M_B_CPU1_SB_CB<2>";
153"M_B_CPU1_SB_CB<3>";
154"M_B_CPU1_SB_CB<4>";
155"M_B_CPU1_SB_CB<5>";
156"M_B_CPU1_SB_CB<6>";
157"M_B_CPU1_SA_CB<0>";
158"M_B_CPU1_SA_CB<2>";
159"M_B_CPU1_SA_CB<3>";
160"M_B_CPU1_SA_CB<5>";
161"M_B_CPU1_SA_CB<6>";
162"M_B_CPU1_SB_CA<6>";
163"M_B_CPU1_SA_CA<6>";
164"M_B_CPU1_SB_CA<5>";
165"M_B_CPU1_SA_CA<5>";
166"M_B_CPU1_SB_CA<4>";
167"M_B_CPU1_SB_CA<3>";
168"M_B_CPU1_SA_CA<3>";
169"M_B_CPU1_SB_CA<2>";
170"M_B_CPU1_SA_CA<2>";
171"M_B_CPU1_SB_CA<1>";
172"M_B_CPU1_SB_CA<0>";
173"M_B_CPU1_SB_CB<7>";
174"M_B_CPU1_SA_CB<1>";
175"M_B_CPU1_SA_CB<4>";
176"M_B_CPU1_SA_CB<7>";
177"PWRGD_CHAF_CPU1";
178"PD_CHB_CPU1_DIMM_SAA";
%"TAP"
"1","(-6075,4325)","0","mstr_standard","I100";
;
CDS_LIB"mstr_standard"
BODY_TYPE"PLUMBING"
HDL_TAP"TRUE";
"B \NAC \NWC"5;
"S \NAC"
BN"7"124;
%"TAP"
"1","(-6075,4575)","0","mstr_standard","I101";
;
CDS_LIB"mstr_standard"
BODY_TYPE"PLUMBING"
HDL_TAP"TRUE";
"B \NAC \NWC"5;
"S \NAC"
BN"12"129;
%"TAP"
"1","(-6075,4525)","0","mstr_standard","I102";
;
CDS_LIB"mstr_standard"
BODY_TYPE"PLUMBING"
HDL_TAP"TRUE";
"B \NAC \NWC"5;
"S \NAC"
BN"11"128;
%"TAP"
"1","(-6075,4475)","0","mstr_standard","I103";
;
CDS_LIB"mstr_standard"
BODY_TYPE"PLUMBING"
HDL_TAP"TRUE";
"B \NAC \NWC"5;
"S \NAC"
BN"10"127;
%"TAP"
"1","(-6075,4425)","0","mstr_standard","I104";
;
CDS_LIB"mstr_standard"
BODY_TYPE"PLUMBING"
HDL_TAP"TRUE";
"B \NAC \NWC"5;
"S \NAC"
BN"9"126;
%"TAP"
"1","(-6075,4375)","0","mstr_standard","I105";
;
CDS_LIB"mstr_standard"
BODY_TYPE"PLUMBING"
HDL_TAP"TRUE";
"B \NAC \NWC"5;
"S \NAC"
BN"8"125;
%"TAP"
"1","(-6075,4825)","0","mstr_standard","I106";
;
CDS_LIB"mstr_standard"
BODY_TYPE"PLUMBING"
HDL_TAP"TRUE";
"B \NAC \NWC"5;
"S \NAC"
BN"17"134;
%"TAP"
"1","(-6075,4775)","0","mstr_standard","I107";
;
CDS_LIB"mstr_standard"
BODY_TYPE"PLUMBING"
HDL_TAP"TRUE";
"B \NAC \NWC"5;
"S \NAC"
BN"16"133;
%"TAP"
"1","(-6075,4625)","0","mstr_standard","I108";
;
CDS_LIB"mstr_standard"
BODY_TYPE"PLUMBING"
HDL_TAP"TRUE";
"B \NAC \NWC"5;
"S \NAC"
BN"13"130;
%"TAP"
"1","(-6075,4725)","0","mstr_standard","I109";
;
CDS_LIB"mstr_standard"
BODY_TYPE"PLUMBING"
HDL_TAP"TRUE";
"B \NAC \NWC"5;
"S \NAC"
BN"15"132;
%"TAP"
"1","(-6075,4675)","0","mstr_standard","I110";
;
CDS_LIB"mstr_standard"
BODY_TYPE"PLUMBING"
HDL_TAP"TRUE";
"B \NAC \NWC"5;
"S \NAC"
BN"14"131;
%"TAP"
"1","(-6075,5025)","0","mstr_standard","I111";
;
CDS_LIB"mstr_standard"
BODY_TYPE"PLUMBING"
HDL_TAP"TRUE";
"B \NAC \NWC"5;
"S \NAC"
BN"21"137;
%"TAP"
"1","(-6075,5075)","0","mstr_standard","I112";
;
CDS_LIB"mstr_standard"
BODY_TYPE"PLUMBING"
HDL_TAP"TRUE";
"B \NAC \NWC"5;
"S \NAC"
BN"22"138;
%"TAP"
"1","(-6075,4925)","0","mstr_standard","I113";
;
CDS_LIB"mstr_standard"
BODY_TYPE"PLUMBING"
HDL_TAP"TRUE";
"B \NAC \NWC"5;
"S \NAC"
BN"19"32;
%"TAP"
"1","(-6075,4975)","0","mstr_standard","I114";
;
CDS_LIB"mstr_standard"
BODY_TYPE"PLUMBING"
HDL_TAP"TRUE";
"B \NAC \NWC"5;
"S \NAC"
BN"20"136;
%"TAP"
"1","(-6075,4875)","0","mstr_standard","I115";
;
CDS_LIB"mstr_standard"
BODY_TYPE"PLUMBING"
HDL_TAP"TRUE";
"B \NAC \NWC"5;
"S \NAC"
BN"18"135;
%"TAP"
"1","(-6075,5125)","0","mstr_standard","I116";
;
CDS_LIB"mstr_standard"
BODY_TYPE"PLUMBING"
HDL_TAP"TRUE";
"B \NAC \NWC"5;
"S \NAC"
BN"23"139;
%"TAP"
"1","(-6075,5175)","0","mstr_standard","I117";
;
CDS_LIB"mstr_standard"
BODY_TYPE"PLUMBING"
HDL_TAP"TRUE";
"B \NAC \NWC"5;
"S \NAC"
BN"24"75;
%"TAP"
"1","(-6075,5225)","0","mstr_standard","I118";
;
CDS_LIB"mstr_standard"
BODY_TYPE"PLUMBING"
HDL_TAP"TRUE";
"B \NAC \NWC"5;
"S \NAC"
BN"25"140;
%"TAP"
"1","(-6075,5375)","0","mstr_standard","I119";
;
CDS_LIB"mstr_standard"
BODY_TYPE"PLUMBING"
HDL_TAP"TRUE";
"B \NAC \NWC"5;
"S \NAC"
BN"28"31;
%"TAP"
"1","(-6075,5325)","0","mstr_standard","I120";
;
CDS_LIB"mstr_standard"
BODY_TYPE"PLUMBING"
HDL_TAP"TRUE";
"B \NAC \NWC"5;
"S \NAC"
BN"27"142;
%"TAP"
"1","(-6075,5275)","0","mstr_standard","I121";
;
CDS_LIB"mstr_standard"
BODY_TYPE"PLUMBING"
HDL_TAP"TRUE";
"B \NAC \NWC"5;
"S \NAC"
BN"26"141;
%"TAP"
"1","(-6075,5475)","0","mstr_standard","I122";
;
CDS_LIB"mstr_standard"
BODY_TYPE"PLUMBING"
HDL_TAP"TRUE";
"B \NAC \NWC"5;
"S \NAC"
BN"30"143;
%"TAP"
"1","(-6075,5425)","0","mstr_standard","I123";
;
CDS_LIB"mstr_standard"
BODY_TYPE"PLUMBING"
HDL_TAP"TRUE";
"B \NAC \NWC"5;
"S \NAC"
BN"29"74;
%"TAP"
"1","(-6075,5525)","0","mstr_standard","I124";
;
CDS_LIB"mstr_standard"
BODY_TYPE"PLUMBING"
HDL_TAP"TRUE";
"B \NAC \NWC"5;
"S \NAC"
BN"31"73;
%"GND"
"1","(-6475,1225)","0","mstr_symbols","I126";
;
CDS_LIB"mstr_symbols"
SIZE"1B"
BOM_COST"MEM"
BODY_TYPE"PLUMBING"
VOLTAGE"0.0"
HDL_POWER"GND";
"A\NAC"11;
%"Q_RES"
"2","(-6475,1450)","0","pure_quanta","I127";
;
LOCATION"R770"
$SEC"1"
CDS_SEC"1"
WATTAGE"1/16W"
MATERIAL"CHIP"
TOLERANCE"1%"
VALUE"15.4K"
PART_NUMBER"CS31542FB02"
PACK_TYPE"0402LF"
CDS_LIB"pure_quanta";
"A"
$PN"1"178;
"B"
$PN"2"11;
%"GND"
"1","(-2175,1725)","0","mstr_symbols","I128";
;
SIZE"1B"
CDS_LIB"mstr_symbols"
BODY_TYPE"PLUMBING"
VOLTAGE"0.0"
HDL_POWER"GND";
"A\NAC"28;
%"SCONN288_DDR506112002KQ"
"3","(-1275,3475)","0","pure_quanta","I160";
;
LOCATION"J26"
$SEC"3"
CDS_SEC"3"
PART_TYPE"SMLF"
VALUE"SCONN288_DDR506112002KQ"
MATERIAL"IO"
PART_NUMBER"DFHST8FS479"
CDS_LMAN_SYM_OUTLINE"-450,1800,450,-1750"
NEEDS_NO_SIZE"TRUE"
CDS_LIB"pure_quanta";
"G3"
$PN"G3"27;
"G2"
$PN"G2"27;
"G1"
$PN"G1"27;
"VSS62"
$PN"141"27;
"VSS61"
$PN"139"27;
"VSS60"
$PN"136"27;
"VSS58"
$PN"132"27;
"VSS104"
$PN"240"28;
"VSS102"
$PN"235"28;
"VSS100"
$PN"230"28;
"VIN_BULK2"
$PN"146"25;
"VIN_BULK1"
$PN"145"25;
"VIN_BULK0"
$PN"1"25;
"VSS126"
$PN"288"28;
"VSS125"
$PN"286"28;
"VSS124"
$PN"284"28;
"VSS123"
$PN"281"28;
"VSS122"
$PN"279"28;
"VSS121"
$PN"277"28;
"VSS120"
$PN"275"28;
"VSS119"
$PN"273"28;
"VSS118"
$PN"270"28;
"VSS117"
$PN"268"28;
"VSS116"
$PN"266"28;
"VSS115"
$PN"264"28;
"VSS114"
$PN"262"28;
"VSS113"
$PN"259"28;
"VSS112"
$PN"257"28;
"VSS111"
$PN"255"28;
"VSS110"
$PN"253"28;
"VSS109"
$PN"251"28;
"VSS108"
$PN"248"28;
"VSS107"
$PN"246"28;
"VSS106"
$PN"244"28;
"VSS105"
$PN"242"28;
"VSS103"
$PN"237"28;
"VSS101"
$PN"233"28;
"VSS99"
$PN"228"28;
"VSS98"
$PN"226"28;
"VSS97"
$PN"224"28;
"VSS96"
$PN"222"28;
"VSS95"
$PN"219"28;
"VSS94"
$PN"216"28;
"VSS93"
$PN"214"28;
"VSS92"
$PN"212"28;
"VSS91"
$PN"210"28;
"VSS90"
$PN"208"28;
"VSS89"
$PN"206"28;
"VSS88"
$PN"204"28;
"VSS87"
$PN"202"28;
"VSS86"
$PN"199"28;
"VSS85"
$PN"197"28;
"VSS84"
$PN"195"28;
"VSS83"
$PN"193"28;
"VSS82"
$PN"191"28;
"VSS81"
$PN"188"28;
"VSS80"
$PN"186"28;
"VSS79"
$PN"184"28;
"VSS78"
$PN"182"28;
"VSS77"
$PN"180"28;
"VSS76"
$PN"177"28;
"VSS75"
$PN"175"28;
"VSS74"
$PN"173"28;
"VSS73"
$PN"171"28;
"VSS72"
$PN"169"28;
"VSS71"
$PN"166"28;
"VSS70"
$PN"164"28;
"VSS69"
$PN"162"28;
"VSS68"
$PN"160"28;
"VSS67"
$PN"158"28;
"VSS66"
$PN"155"28;
"VSS65"
$PN"153"28;
"VSS64"
$PN"151"28;
"VSS63"
$PN"143"27;
"VSS59"
$PN"134"27;
"VSS57"
$PN"130"27;
"VSS56"
$PN"128"27;
"VSS55"
$PN"125"27;
"VSS54"
$PN"123"27;
"VSS53"
$PN"121"27;
"VSS52"
$PN"119"27;
"VSS51"
$PN"117"27;
"VSS50"
$PN"114"27;
"VSS49"
$PN"112"27;
"VSS48"
$PN"110"27;
"VSS47"
$PN"108"27;
"VSS46"
$PN"106"27;
"VSS45"
$PN"103"27;
"VSS44"
$PN"101"27;
"VSS43"
$PN"99"27;
"VSS42"
$PN"97"27;
"VSS41"
$PN"95"27;
"VSS40"
$PN"92"27;
"VSS39"
$PN"90"27;
"VSS38"
$PN"88"27;
"VSS37"
$PN"85"27;
"VSS36"
$PN"83"27;
"VSS35"
$PN"81"27;
"VSS34"
$PN"79"27;
"VSS33"
$PN"77"27;
"VSS32"
$PN"75"27;
"VSS31"
$PN"73"27;
"VSS30"
$PN"71"27;
"VSS29"
$PN"69"27;
"VSS28"
$PN"67"27;
"VSS27"
$PN"65"27;
"VSS26"
$PN"63"27;
"VSS25"
$PN"61"27;
"VSS24"
$PN"59"27;
"VSS23"
$PN"57"27;
"VSS22"
$PN"54"27;
"VSS21"
$PN"52"27;
"VSS20"
$PN"50"27;
"VSS19"
$PN"48"27;
"VSS18"
$PN"46"27;
"VSS17"
$PN"43"27;
"VSS16"
$PN"41"27;
"VSS15"
$PN"39"27;
"VSS14"
$PN"37"27;
"VSS13"
$PN"35"27;
"VSS12"
$PN"32"27;
"VSS11"
$PN"30"27;
"VSS10"
$PN"28"27;
"VSS9"
$PN"26"27;
"VSS8"
$PN"24"27;
"VSS7"
$PN"21"27;
"VSS6"
$PN"19"27;
"VSS5"
$PN"17"27;
"VSS4"
$PN"15"27;
"VSS3"
$PN"13"27;
"VSS2"
$PN"10"27;
"VSS1"
$PN"8"27;
"VSS0"
$PN"6"27;
%"GND"
"1","(-375,1550)","0","mstr_symbols","I161";
;
CDS_LIB"mstr_symbols"
SIZE"1B"
BODY_TYPE"PLUMBING"
VOLTAGE"0.0"
HDL_POWER"GND";
"A\NAC"27;
%"Q_CAP"
"1","(-8725,3325)","2","pure_quanta","I185";
;
LOCATION"C140"
$SEC"1"
CDS_SEC"1"
MATERIAL"X7R"
TOLERANCE"10%"
VALUE"0.1UF"
VOLTAGE"25V"
PART_NUMBER"CH4104K1B00"
PACK_TYPE"0402"
BOM_COST"MEM"
CDS_LIB"pure_quanta"
ROOM"MEM_CH_A_CPU0_DIMM1";
"B"
$PN"2"12;
"A"
$PN"1"21;
%"GND"
"1","(-8725,3100)","0","mstr_symbols","I186";
;
BOM_COST"MEM"
SIZE"1B"
CDS_LIB"mstr_symbols"
BODY_TYPE"PLUMBING"
VOLTAGE"0"
ROOM"MEM_EFGH_DECOUPLING_CAPS"
HDL_POWER"GND";
"A\NAC"12;
%"Q_RES"
"1","(-8625,2275)","2","pure_quanta","I188";
;
LOCATION"R304"
$SEC"1"
CDS_SEC"1"
VALUE"0"
BOM_COST"MEM"
CDS_LIB"pure_quanta"
WATTAGE"1/16W"
MATERIAL"CHIP"
TOLERANCE"5%"
PART_NUMBER"CS00002JB38"
PACK_TYPE"0402LF"
ROOM"RST_CPU0_PLD_TO_DIMM";
"B"
$PN"2"177;
"A"
$PN"1"16;
%"VCC_CORE"
"1","(-8500,2600)","0","mstr_symbols","I189";
;
HDL_POWER"P3V3_STBY"
CDS_LIB"mstr_symbols"
VOLTAGE"3.3"
ROOM"PVCCINFAON_CPU0_CTRL";
"A"13;
%"Q_RES"
"2","(-8500,2425)","0","pure_quanta","I190";
;
LOCATION"R104"
$SEC"1"
CDS_SEC"1"
MATERIAL"EMPTY"
VALUE"1K"
PACK_TYPE"0402LF"
WATTAGE"1/16W"
TOLERANCE"5%"
CDS_LIB"pure_quanta"
BOM_COST"MEM"
PART_NUMBER"TMP_QCS21002JB34"
ROOM"MEM_CH_A_CPU0_DIMM1";
"A"
$PN"1"13;
"B"
$PN"2"16;
%"TAP"
"1","(-3250,3750)","0","mstr_standard","I191";
;
CDS_LIB"mstr_standard"
BODY_TYPE"PLUMBING"
HDL_TAP"TRUE";
"B \NAC \NWC"7;
"S \NAC"
BN"2"57;
%"TAP"
"1","(-3250,4450)","0","mstr_standard","I195";
;
CDS_LIB"mstr_standard"
BODY_TYPE"PLUMBING"
HDL_TAP"TRUE";
"B \NAC \NWC"7;
"S \NAC"
BN"9"36;
%"TAP"
"1","(-3250,4350)","0","mstr_standard","I196";
;
CDS_LIB"mstr_standard"
BODY_TYPE"PLUMBING"
HDL_TAP"TRUE";
"B \NAC \NWC"7;
"S \NAC"
BN"8"30;
%"TAP"
"1","(-3250,4250)","0","mstr_standard","I197";
;
CDS_LIB"mstr_standard"
BODY_TYPE"PLUMBING"
HDL_TAP"TRUE";
"B \NAC \NWC"7;
"S \NAC"
BN"7"70;
%"TAP"
"1","(-3250,4150)","0","mstr_standard","I198";
;
CDS_LIB"mstr_standard"
BODY_TYPE"PLUMBING"
HDL_TAP"TRUE";
"B \NAC \NWC"7;
"S \NAC"
BN"6"41;
%"TAP"
"1","(-3250,4050)","0","mstr_standard","I199";
;
CDS_LIB"mstr_standard"
BODY_TYPE"PLUMBING"
HDL_TAP"TRUE";
"B \NAC \NWC"7;
"S \NAC"
BN"5"45;
%"TAP"
"1","(-3450,4400)","0","mstr_standard","I200";
;
CDS_LIB"mstr_standard"
BODY_TYPE"PLUMBING"
HDL_TAP"TRUE";
"B \NAC \NWC"8;
"S \NAC"
BN"8"37;
%"TAP"
"1","(-3450,4500)","0","mstr_standard","I201";
;
CDS_LIB"mstr_standard"
BODY_TYPE"PLUMBING"
HDL_TAP"TRUE";
"B \NAC \NWC"8;
"S \NAC"
BN"9"33;
%"TAP"
"1","(-3450,4300)","0","mstr_standard","I202";
;
CDS_LIB"mstr_standard"
BODY_TYPE"PLUMBING"
HDL_TAP"TRUE";
"B \NAC \NWC"8;
"S \NAC"
BN"7"29;
%"TAP"
"1","(-3450,4100)","0","mstr_standard","I203";
;
CDS_LIB"mstr_standard"
BODY_TYPE"PLUMBING"
HDL_TAP"TRUE";
"B \NAC \NWC"8;
"S \NAC"
BN"5"44;
%"TAP"
"1","(-3450,4200)","0","mstr_standard","I204";
;
CDS_LIB"mstr_standard"
BODY_TYPE"PLUMBING"
HDL_TAP"TRUE";
"B \NAC \NWC"8;
"S \NAC"
BN"6"69;
%"TAP"
"1","(-3250,3950)","0","mstr_standard","I207";
;
CDS_LIB"mstr_standard"
BODY_TYPE"PLUMBING"
HDL_TAP"TRUE";
"B \NAC \NWC"7;
"S \NAC"
BN"4"49;
%"TAP"
"1","(-3250,3850)","0","mstr_standard","I208";
;
CDS_LIB"mstr_standard"
BODY_TYPE"PLUMBING"
HDL_TAP"TRUE";
"B \NAC \NWC"7;
"S \NAC"
BN"3"53;
%"TAP"
"1","(-3250,3550)","0","mstr_standard","I209";
;
CDS_LIB"mstr_standard"
BODY_TYPE"PLUMBING"
HDL_TAP"TRUE";
"B \NAC \NWC"7;
"S \NAC"
BN"0"65;
%"TAP"
"1","(-3250,3650)","0","mstr_standard","I210";
;
CDS_LIB"mstr_standard"
BODY_TYPE"PLUMBING"
HDL_TAP"TRUE";
"B \NAC \NWC"7;
"S \NAC"
BN"1"61;
%"TAP"
"1","(-3250,3300)","0","mstr_standard","I211";
;
CDS_LIB"mstr_standard"
BODY_TYPE"PLUMBING"
HDL_TAP"TRUE";
"B \NAC \NWC"9;
"S \NAC"
BN"8"67;
%"TAP"
"1","(-3250,3400)","0","mstr_standard","I212";
;
CDS_LIB"mstr_standard"
BODY_TYPE"PLUMBING"
HDL_TAP"TRUE";
"B \NAC \NWC"9;
"S \NAC"
BN"9"35;
%"TAP"
"1","(-3250,3200)","0","mstr_standard","I213";
;
CDS_LIB"mstr_standard"
BODY_TYPE"PLUMBING"
HDL_TAP"TRUE";
"B \NAC \NWC"9;
"S \NAC"
BN"7"38;
%"TAP"
"1","(-3250,3100)","0","mstr_standard","I214";
;
CDS_LIB"mstr_standard"
BODY_TYPE"PLUMBING"
HDL_TAP"TRUE";
"B \NAC \NWC"9;
"S \NAC"
BN"6"40;
%"TAP"
"1","(-3450,3900)","0","mstr_standard","I215";
;
CDS_LIB"mstr_standard"
BODY_TYPE"PLUMBING"
HDL_TAP"TRUE";
"B \NAC \NWC"8;
"S \NAC"
BN"3"52;
%"TAP"
"1","(-3450,4000)","0","mstr_standard","I216";
;
CDS_LIB"mstr_standard"
BODY_TYPE"PLUMBING"
HDL_TAP"TRUE";
"B \NAC \NWC"8;
"S \NAC"
BN"4"48;
%"TAP"
"1","(-3450,3800)","0","mstr_standard","I217";
;
CDS_LIB"mstr_standard"
BODY_TYPE"PLUMBING"
HDL_TAP"TRUE";
"B \NAC \NWC"8;
"S \NAC"
BN"2"56;
%"TAP"
"1","(-3450,3700)","0","mstr_standard","I218";
;
CDS_LIB"mstr_standard"
BODY_TYPE"PLUMBING"
HDL_TAP"TRUE";
"B \NAC \NWC"8;
"S \NAC"
BN"1"60;
%"TAP"
"1","(-3450,3600)","0","mstr_standard","I219";
;
CDS_LIB"mstr_standard"
BODY_TYPE"PLUMBING"
HDL_TAP"TRUE";
"B \NAC \NWC"8;
"S \NAC"
BN"0"64;
%"SCONN288_DDR506112002KQ"
"1","(-6925,3775)","0","pure_quanta","I22";
;
LOCATION"J26"
$SEC"1"
CDS_SEC"1"
PART_TYPE"SMLF"
VALUE"SCONN288_DDR506112002KQ"
MATERIAL"IO"
PART_NUMBER"DFHST8FS479"
CDS_LMAN_SYM_OUTLINE"-450,1900,450,-1850"
NEEDS_NO_SIZE"TRUE"
CDS_LIB"pure_quanta";
"PWR_GOOD||FAIL_N"
$PN"147"16;
"DQ31_A"
$PN"194"73;
"CB7_A"
$PN"205"176;
"CB4_A"
$PN"58"175;
"CB1_A"
$PN"53"174;
"CB7_B"
$PN"236"173;
"ALERT_N \B"
$PN"62"22;
"CA0_A"
$PN"66"24;
"CA0_B"
$PN"76"172;
"CA1_A"
$PN"211"71;
"CA1_B"
$PN"221"171;
"CA2_A"
$PN"68"170;
"CA2_B"
$PN"78"169;
"CA3_A"
$PN"213"168;
"CA3_B"
$PN"223"167;
"CA4_A"
$PN"70"72;
"CA4_B"
$PN"80"166;
"CA5_A"
$PN"215"165;
"CA5_B"
$PN"225"164;
"CA6_A"
$PN"72"163;
"CA6_B"
$PN"82"162;
"CB6_A"
$PN"203"161;
"CB5_A"
$PN"60"160;
"CB3_A"
$PN"198"159;
"CB2_A"
$PN"196"158;
"CB0_A"
$PN"51"157;
"CB6_B"
$PN"234"156;
"CB5_B"
$PN"91"155;
"CB4_B"
$PN"89"154;
"CB3_B"
$PN"243"153;
"CB2_B"
$PN"241"152;
"CB1_B"
$PN"98"151;
"CB0_B"
$PN"96"150;
"CK_C \B"
$PN"218"149;
"CK_T"
$PN"217"148;
"CS0_A_N"
$PN"64"147;
"CS0_B_N"
$PN"84"146;
"CS1_A_N"
$PN"209"145;
"CS1_B_N"
$PN"229"144;
"DQ30_A"
$PN"192"143;
"DQ29_A"
$PN"49"74;
"DQ28_A"
$PN"47"31;
"DQ27_A"
$PN"187"142;
"DQ26_A"
$PN"185"141;
"DQ25_A"
$PN"42"140;
"DQ24_A"
$PN"40"75;
"DQ23_A"
$PN"183"139;
"DQ22_A"
$PN"181"138;
"DQ21_A"
$PN"38"137;
"DQ20_A"
$PN"36"136;
"DQ19_A"
$PN"176"32;
"DQ18_A"
$PN"174"135;
"DQ17_A"
$PN"31"134;
"DQ16_A"
$PN"29"133;
"DQ15_A"
$PN"172"132;
"DQ14_A"
$PN"170"131;
"DQ13_A"
$PN"27"130;
"DQ12_A"
$PN"25"129;
"DQ11_A"
$PN"165"128;
"DQ10_A"
$PN"163"127;
"DQ9_A"
$PN"20"126;
"DQ8_A"
$PN"18"125;
"DQ7_A"
$PN"161"124;
"DQ6_A"
$PN"159"123;
"DQ5_A"
$PN"16"122;
"DQ4_A"
$PN"14"121;
"DQ3_A"
$PN"154"120;
"DQ2_A"
$PN"152"119;
"DQ1_A"
$PN"9"118;
"DQ0_A"
$PN"7"117;
"DQ31_B"
$PN"287"116;
"DQ30_B"
$PN"285"115;
"DQ29_B"
$PN"142"114;
"DQ28_B"
$PN"140"113;
"DQ27_B"
$PN"280"112;
"DQ26_B"
$PN"278"111;
"DQ25_B"
$PN"135"110;
"DQ24_B"
$PN"133"109;
"DQ23_B"
$PN"276"108;
"DQ22_B"
$PN"274"107;
"DQ21_B"
$PN"131"106;
"DQ20_B"
$PN"129"105;
"DQ19_B"
$PN"269"104;
"DQ18_B"
$PN"267"103;
"DQ17_B"
$PN"124"102;
"DQ16_B"
$PN"122"101;
"DQ15_B"
$PN"265"100;
"DQ14_B"
$PN"263"99;
"DQ13_B"
$PN"120"98;
"DQ12_B"
$PN"118"97;
"DQ11_B"
$PN"258"96;
"DQ10_B"
$PN"256"95;
"DQ9_B"
$PN"113"94;
"DQ8_B"
$PN"111"93;
"DQ7_B"
$PN"254"92;
"DQ6_B"
$PN"252"91;
"DQ5_B"
$PN"109"90;
"DQ4_B"
$PN"107"89;
"DQ3_B"
$PN"247"88;
"DQ2_B"
$PN"245"87;
"DQ1_B"
$PN"102"86;
"DQ0_B"
$PN"100"85;
"HAS"
$PN"148"20;
"HSCL"
$PN"4"15;
"HSDA"
$PN"5"19;
"LBD||RSP_A_N"
$PN"86"84;
"LBS||RSP_B_N"
$PN"87"83;
"PAR_A"
$PN"74"82;
"PAR_B"
$PN"227"81;
"RESET_N \B"
$PN"207"80;
"RFU6"
$PN"232"18;
"RFU5"
$PN"231"17;
"RFU4"
$PN"220"79;
"RFU3"
$PN"150"78;
"RFU2"
$PN"149"23;
"RFU1"
$PN"144"77;
"RFU0"
$PN"2"76;
"VIN_MGMT"
$PN"3"21;
%"TAP"
"1","(-3450,3350)","0","mstr_standard","I220";
;
CDS_LIB"mstr_standard"
BODY_TYPE"PLUMBING"
HDL_TAP"TRUE";
"B \NAC \NWC"10;
"S \NAC"
BN"8"68;
%"TAP"
"1","(-3450,3450)","0","mstr_standard","I221";
;
CDS_LIB"mstr_standard"
BODY_TYPE"PLUMBING"
HDL_TAP"TRUE";
"B \NAC \NWC"10;
"S \NAC"
BN"9"34;
%"TAP"
"1","(-3450,3250)","0","mstr_standard","I222";
;
CDS_LIB"mstr_standard"
BODY_TYPE"PLUMBING"
HDL_TAP"TRUE";
"B \NAC \NWC"10;
"S \NAC"
BN"7"66;
%"TAP"
"1","(-3450,3150)","0","mstr_standard","I223";
;
CDS_LIB"mstr_standard"
BODY_TYPE"PLUMBING"
HDL_TAP"TRUE";
"B \NAC \NWC"10;
"S \NAC"
BN"6"39;
%"TAP"
"1","(-3450,3050)","0","mstr_standard","I224";
;
CDS_LIB"mstr_standard"
BODY_TYPE"PLUMBING"
HDL_TAP"TRUE";
"B \NAC \NWC"10;
"S \NAC"
BN"5"42;
%"TAP"
"1","(-3250,3000)","0","mstr_standard","I225";
;
CDS_LIB"mstr_standard"
BODY_TYPE"PLUMBING"
HDL_TAP"TRUE";
"B \NAC \NWC"9;
"S \NAC"
BN"5"43;
%"TAP"
"1","(-3250,2900)","0","mstr_standard","I226";
;
CDS_LIB"mstr_standard"
BODY_TYPE"PLUMBING"
HDL_TAP"TRUE";
"B \NAC \NWC"9;
"S \NAC"
BN"4"47;
%"TAP"
"1","(-3250,2800)","0","mstr_standard","I227";
;
CDS_LIB"mstr_standard"
BODY_TYPE"PLUMBING"
HDL_TAP"TRUE";
"B \NAC \NWC"9;
"S \NAC"
BN"3"51;
%"TAP"
"1","(-3250,2700)","0","mstr_standard","I228";
;
CDS_LIB"mstr_standard"
BODY_TYPE"PLUMBING"
HDL_TAP"TRUE";
"B \NAC \NWC"9;
"S \NAC"
BN"2"55;
%"TAP"
"1","(-3250,2600)","0","mstr_standard","I229";
;
CDS_LIB"mstr_standard"
BODY_TYPE"PLUMBING"
HDL_TAP"TRUE";
"B \NAC \NWC"9;
"S \NAC"
BN"1"59;
%"TAP"
"1","(-7775,3325)","2","mstr_standard","I23";
;
CDS_LIB"mstr_standard"
BODY_TYPE"PLUMBING"
HDL_TAP"TRUE";
"B \NAC \NWC"4;
"S \NAC"
BN"0"150;
%"TAP"
"1","(-3250,2500)","0","mstr_standard","I230";
;
CDS_LIB"mstr_standard"
BODY_TYPE"PLUMBING"
HDL_TAP"TRUE";
"B \NAC \NWC"9;
"S \NAC"
BN"0"63;
%"TAP"
"1","(-3450,2850)","0","mstr_standard","I231";
;
CDS_LIB"mstr_standard"
BODY_TYPE"PLUMBING"
HDL_TAP"TRUE";
"B \NAC \NWC"10;
"S \NAC"
BN"3"50;
%"TAP"
"1","(-3450,2950)","0","mstr_standard","I232";
;
CDS_LIB"mstr_standard"
BODY_TYPE"PLUMBING"
HDL_TAP"TRUE";
"B \NAC \NWC"10;
"S \NAC"
BN"4"46;
%"TAP"
"1","(-3450,2750)","0","mstr_standard","I233";
;
CDS_LIB"mstr_standard"
BODY_TYPE"PLUMBING"
HDL_TAP"TRUE";
"B \NAC \NWC"10;
"S \NAC"
BN"2"54;
%"TAP"
"1","(-3450,2550)","0","mstr_standard","I234";
;
CDS_LIB"mstr_standard"
BODY_TYPE"PLUMBING"
HDL_TAP"TRUE";
"B \NAC \NWC"10;
"S \NAC"
BN"0"62;
%"TAP"
"1","(-3450,2650)","0","mstr_standard","I235";
;
CDS_LIB"mstr_standard"
BODY_TYPE"PLUMBING"
HDL_TAP"TRUE";
"B \NAC \NWC"10;
"S \NAC"
BN"1"58;
%"SCONN288_DDR506112002KQ"
"2","(-4400,3500)","0","pure_quanta","I236";
;
LOCATION"J26"
$SEC"2"
CDS_SEC"2"
VALUE"SCONN288_DDR506112002KQ"
PART_TYPE"SMLF"
PART_NUMBER"DFHST8FS479"
MATERIAL"IO"
CDS_LMAN_SYM_OUTLINE"-600,1150,600,-1150"
NEEDS_NO_SIZE"TRUE"
CDS_LIB"pure_quanta";
"DQS7_A_C||TDQS7_A_C \B"
$PN"178"70;
"DQS6_A_T||TDQS6_A_T"
$PN"168"69;
"DQS8_B_T||TDQS8_B_T"
$PN"283"68;
"DQS8_B_C||TDQS8_B_C \B"
$PN"282"67;
"DQS7_B_T||TDQS7_B_T"
$PN"272"66;
"DQS0_A_C \B"
$PN"12"65;
"DQS0_A_T"
$PN"11"64;
"DQS0_B_C \B"
$PN"105"63;
"DQS0_B_T"
$PN"104"62;
"DQS1_A_C \B"
$PN"23"61;
"DQS1_A_T"
$PN"22"60;
"DQS1_B_C \B"
$PN"116"59;
"DQS1_B_T"
$PN"115"58;
"DQS2_A_C \B"
$PN"34"57;
"DQS2_A_T"
$PN"33"56;
"DQS2_B_C \B"
$PN"127"55;
"DQS2_B_T"
$PN"126"54;
"DQS3_A_C \B"
$PN"45"53;
"DQS3_A_T"
$PN"44"52;
"DQS3_B_C \B"
$PN"138"51;
"DQS3_B_T"
$PN"137"50;
"DQS4_A_C \B"
$PN"56"49;
"DQS4_A_T"
$PN"55"48;
"DQS4_B_C \B"
$PN"238"47;
"DQS4_B_T"
$PN"239"46;
"DQS5_A_C||TDQS5_A_C||DQS5_A_T||TDQS5_A_T \B"
$PN"156"45;
"DQS5_A_T||TDQS5_A_T"
$PN"157"44;
"DQS5_B_C||TDQS5_B_C \B"
$PN"249"43;
"DQS5_B_T||TDQS5_B_T"
$PN"250"42;
"DQS6_A_C||TDQS6_A_C||DQS6_A_T||TDQS6_A_T \B"
$PN"167"41;
"DQS6_B_C||TDQS6_B_C \B"
$PN"260"40;
"DQS6_B_T||TDQS6_B_T"
$PN"261"39;
"DQS7_A_T||TDQS7_A_T"
$PN"179"29;
"DQS7_B_C||TDQS7_B_C \B"
$PN"271"38;
"DQS8_A_C||TDQS8_A_C \B"
$PN"189"30;
"DQS8_A_T||TDQS8_A_T"
$PN"190"37;
"DQS9_A_C||TDQS9_A_C \B"
$PN"200"36;
"DQS9_A_T||TDQS9_A_T"
$PN"201"33;
"DQS9_B_C||TDQS9_B_C \B"
$PN"94"35;
"DQS9_B_T||TDQS9_B_T||DBI4_B_N"
$PN"93"34;
%"GND"
"1","(-2875,5175)","0","pure_quanta_power","I237";
;
CDS_LIB"pure_quanta_power"
BOM_COST"MEM"
SIZE"1B"
ROOM"MEM_EFGH_DECOUPLING_CAPS"
HDL_POWER"GND";
"A<SIZE-1..0>\NAC"26;
%"Q_CAP"
"1","(-2875,5525)","2","pure_quanta","I238";
;
LOCATION"C175"
$SEC"1"
CDS_SEC"1"
VOLTAGE"25V"
VALUE"10UF"
MATERIAL"X6S"
PART_NUMBER"CH6104KEA00"
TOLERANCE"10%"
PACK_TYPE"C0805"
BOM_COST"MEM"
CDS_LIB"pure_quanta"
ROOM"MEM_CH_A_CPU0_DIMM1";
"B"
$PN"2"26;
"A"
$PN"1"25;
%"Q_CAP"
"1","(-2300,5525)","2","pure_quanta","I239";
;
LOCATION"C177"
$SEC"1"
CDS_SEC"1"
MATERIAL"X6S"
VALUE"10UF"
PACK_TYPE"C0805"
PART_NUMBER"CH6104KEA00"
VOLTAGE"25V"
TOLERANCE"10%"
BOM_COST"MEM"
CDS_LIB"pure_quanta"
ROOM"MEM_CH_A_CPU0_DIMM1";
"B"
$PN"2"26;
"A"
$PN"1"25;
%"TAP"
"1","(-7775,3375)","2","mstr_standard","I24";
;
CDS_LIB"mstr_standard"
BODY_TYPE"PLUMBING"
HDL_TAP"TRUE";
"B \NAC \NWC"4;
"S \NAC"
BN"1"151;
%"UNIVERSAL_POWER"
"1","(-2875,5850)","0","pure_quanta_power","I240";
;
HDL_POWER"P12V_MEM_2"
CDS_LIB"pure_quanta_power";
"A"25;
%"Q_RES"
"1","(-7825,2825)","0","pure_quanta","I242";
;
$LOCATION"R1581"
CDS_LOCATION"R1581"
$SEC"1"
CDS_SEC"1"
VALUE"49.9"
CDS_LIB"pure_quanta"
MATERIAL"CHIP"
PACK_TYPE"0402LF"
WATTAGE"1/16W"
TOLERANCE"1%"
PART_NUMBER"CS04992FB07";
"B"
$PN"2"15;
"A"
$PN"1"14;
%"TAP"
"1","(-7775,3425)","2","mstr_standard","I25";
;
CDS_LIB"mstr_standard"
BODY_TYPE"PLUMBING"
HDL_TAP"TRUE";
"B \NAC \NWC"4;
"S \NAC"
BN"2"152;
%"TAP"
"1","(-7775,3525)","2","mstr_standard","I26";
;
CDS_LIB"mstr_standard"
BODY_TYPE"PLUMBING"
HDL_TAP"TRUE";
"B \NAC \NWC"4;
"S \NAC"
BN"4"154;
%"TAP"
"1","(-7775,3475)","2","mstr_standard","I27";
;
CDS_LIB"mstr_standard"
BODY_TYPE"PLUMBING"
HDL_TAP"TRUE";
"B \NAC \NWC"4;
"S \NAC"
BN"3"153;
%"TAP"
"1","(-7775,3575)","2","mstr_standard","I28";
;
CDS_LIB"mstr_standard"
BODY_TYPE"PLUMBING"
HDL_TAP"TRUE";
"B \NAC \NWC"4;
"S \NAC"
BN"5"155;
%"TAP"
"1","(-7775,3675)","2","mstr_standard","I29";
;
CDS_LIB"mstr_standard"
BODY_TYPE"PLUMBING"
HDL_TAP"TRUE";
"B \NAC \NWC"4;
"S \NAC"
BN"7"173;
%"TAP"
"1","(-7775,3625)","2","mstr_standard","I30";
;
CDS_LIB"mstr_standard"
BODY_TYPE"PLUMBING"
HDL_TAP"TRUE";
"B \NAC \NWC"4;
"S \NAC"
BN"6"156;
%"TAP"
"1","(-7775,3775)","2","mstr_standard","I31";
;
CDS_LIB"mstr_standard"
BODY_TYPE"PLUMBING"
HDL_TAP"TRUE";
"B \NAC \NWC"1;
"S \NAC"
BN"0"157;
%"TAP"
"1","(-7775,3825)","2","mstr_standard","I32";
;
CDS_LIB"mstr_standard"
BODY_TYPE"PLUMBING"
HDL_TAP"TRUE";
"B \NAC \NWC"1;
"S \NAC"
BN"1"174;
%"TAP"
"1","(-7775,3875)","2","mstr_standard","I33";
;
CDS_LIB"mstr_standard"
BODY_TYPE"PLUMBING"
HDL_TAP"TRUE";
"B \NAC \NWC"1;
"S \NAC"
BN"2"158;
%"TAP"
"1","(-7775,3925)","2","mstr_standard","I34";
;
CDS_LIB"mstr_standard"
BODY_TYPE"PLUMBING"
HDL_TAP"TRUE";
"B \NAC \NWC"1;
"S \NAC"
BN"3"159;
%"TAP"
"1","(-7775,4025)","2","mstr_standard","I35";
;
CDS_LIB"mstr_standard"
BODY_TYPE"PLUMBING"
HDL_TAP"TRUE";
"B \NAC \NWC"1;
"S \NAC"
BN"5"160;
%"TAP"
"1","(-7775,3975)","2","mstr_standard","I36";
;
CDS_LIB"mstr_standard"
BODY_TYPE"PLUMBING"
HDL_TAP"TRUE";
"B \NAC \NWC"1;
"S \NAC"
BN"4"175;
%"TAP"
"1","(-7775,4075)","2","mstr_standard","I37";
;
CDS_LIB"mstr_standard"
BODY_TYPE"PLUMBING"
HDL_TAP"TRUE";
"B \NAC \NWC"1;
"S \NAC"
BN"6"161;
%"TAP"
"1","(-6075,2375)","0","mstr_standard","I38";
;
CDS_LIB"mstr_standard"
BODY_TYPE"PLUMBING"
HDL_TAP"TRUE";
"B \NAC \NWC"6;
"S \NAC"
BN"1"86;
%"TAP"
"1","(-6075,2325)","0","mstr_standard","I39";
;
CDS_LIB"mstr_standard"
BODY_TYPE"PLUMBING"
HDL_TAP"TRUE";
"B \NAC \NWC"6;
"S \NAC"
BN"0"85;
%"TAP"
"1","(-6075,2425)","0","mstr_standard","I40";
;
CDS_LIB"mstr_standard"
BODY_TYPE"PLUMBING"
HDL_TAP"TRUE";
"B \NAC \NWC"6;
"S \NAC"
BN"2"87;
%"TAP"
"1","(-6075,2475)","0","mstr_standard","I41";
;
CDS_LIB"mstr_standard"
BODY_TYPE"PLUMBING"
HDL_TAP"TRUE";
"B \NAC \NWC"6;
"S \NAC"
BN"3"88;
%"TAP"
"1","(-6075,2525)","0","mstr_standard","I42";
;
CDS_LIB"mstr_standard"
BODY_TYPE"PLUMBING"
HDL_TAP"TRUE";
"B \NAC \NWC"6;
"S \NAC"
BN"4"89;
%"TAP"
"1","(-6075,2575)","0","mstr_standard","I43";
;
CDS_LIB"mstr_standard"
BODY_TYPE"PLUMBING"
HDL_TAP"TRUE";
"B \NAC \NWC"6;
"S \NAC"
BN"5"90;
%"TAP"
"1","(-6075,2675)","0","mstr_standard","I44";
;
CDS_LIB"mstr_standard"
BODY_TYPE"PLUMBING"
HDL_TAP"TRUE";
"B \NAC \NWC"6;
"S \NAC"
BN"7"92;
%"TAP"
"1","(-6075,2625)","0","mstr_standard","I45";
;
CDS_LIB"mstr_standard"
BODY_TYPE"PLUMBING"
HDL_TAP"TRUE";
"B \NAC \NWC"6;
"S \NAC"
BN"6"91;
%"TAP"
"1","(-6075,2775)","0","mstr_standard","I46";
;
CDS_LIB"mstr_standard"
BODY_TYPE"PLUMBING"
HDL_TAP"TRUE";
"B \NAC \NWC"6;
"S \NAC"
BN"9"94;
%"TAP"
"1","(-6075,2725)","0","mstr_standard","I47";
;
CDS_LIB"mstr_standard"
BODY_TYPE"PLUMBING"
HDL_TAP"TRUE";
"B \NAC \NWC"6;
"S \NAC"
BN"8"93;
%"TAP"
"1","(-6075,2975)","0","mstr_standard","I48";
;
CDS_LIB"mstr_standard"
BODY_TYPE"PLUMBING"
HDL_TAP"TRUE";
"B \NAC \NWC"6;
"S \NAC"
BN"13"98;
%"TAP"
"1","(-6075,3025)","0","mstr_standard","I49";
;
CDS_LIB"mstr_standard"
BODY_TYPE"PLUMBING"
HDL_TAP"TRUE";
"B \NAC \NWC"6;
"S \NAC"
BN"14"99;
%"TAP"
"1","(-6075,2925)","0","mstr_standard","I50";
;
CDS_LIB"mstr_standard"
BODY_TYPE"PLUMBING"
HDL_TAP"TRUE";
"B \NAC \NWC"6;
"S \NAC"
BN"12"97;
%"TAP"
"1","(-6075,2875)","0","mstr_standard","I51";
;
CDS_LIB"mstr_standard"
BODY_TYPE"PLUMBING"
HDL_TAP"TRUE";
"B \NAC \NWC"6;
"S \NAC"
BN"11"96;
%"TAP"
"1","(-6075,2825)","0","mstr_standard","I52";
;
CDS_LIB"mstr_standard"
BODY_TYPE"PLUMBING"
HDL_TAP"TRUE";
"B \NAC \NWC"6;
"S \NAC"
BN"10"95;
%"TAP"
"1","(-6075,3075)","0","mstr_standard","I53";
;
CDS_LIB"mstr_standard"
BODY_TYPE"PLUMBING"
HDL_TAP"TRUE";
"B \NAC \NWC"6;
"S \NAC"
BN"15"100;
%"TAP"
"1","(-6075,3175)","0","mstr_standard","I54";
;
CDS_LIB"mstr_standard"
BODY_TYPE"PLUMBING"
HDL_TAP"TRUE";
"B \NAC \NWC"6;
"S \NAC"
BN"17"102;
%"TAP"
"1","(-6075,3125)","0","mstr_standard","I55";
;
CDS_LIB"mstr_standard"
BODY_TYPE"PLUMBING"
HDL_TAP"TRUE";
"B \NAC \NWC"6;
"S \NAC"
BN"16"101;
%"TAP"
"1","(-6075,3225)","0","mstr_standard","I56";
;
CDS_LIB"mstr_standard"
BODY_TYPE"PLUMBING"
HDL_TAP"TRUE";
"B \NAC \NWC"6;
"S \NAC"
BN"18"103;
%"TAP"
"1","(-6075,3275)","0","mstr_standard","I57";
;
CDS_LIB"mstr_standard"
BODY_TYPE"PLUMBING"
HDL_TAP"TRUE";
"B \NAC \NWC"6;
"S \NAC"
BN"19"104;
%"TAP"
"1","(-6075,3325)","0","mstr_standard","I58";
;
CDS_LIB"mstr_standard"
BODY_TYPE"PLUMBING"
HDL_TAP"TRUE";
"B \NAC \NWC"6;
"S \NAC"
BN"20"105;
%"TAP"
"1","(-6075,3475)","0","mstr_standard","I59";
;
CDS_LIB"mstr_standard"
BODY_TYPE"PLUMBING"
HDL_TAP"TRUE";
"B \NAC \NWC"6;
"S \NAC"
BN"23"108;
%"TAP"
"1","(-6075,3525)","0","mstr_standard","I60";
;
CDS_LIB"mstr_standard"
BODY_TYPE"PLUMBING"
HDL_TAP"TRUE";
"B \NAC \NWC"6;
"S \NAC"
BN"24"109;
%"TAP"
"1","(-6075,3575)","0","mstr_standard","I61";
;
CDS_LIB"mstr_standard"
BODY_TYPE"PLUMBING"
HDL_TAP"TRUE";
"B \NAC \NWC"6;
"S \NAC"
BN"25"110;
%"TAP"
"1","(-6075,3425)","0","mstr_standard","I62";
;
CDS_LIB"mstr_standard"
BODY_TYPE"PLUMBING"
HDL_TAP"TRUE";
"B \NAC \NWC"6;
"S \NAC"
BN"22"107;
%"TAP"
"1","(-6075,3375)","0","mstr_standard","I63";
;
CDS_LIB"mstr_standard"
BODY_TYPE"PLUMBING"
HDL_TAP"TRUE";
"B \NAC \NWC"6;
"S \NAC"
BN"21"106;
%"TAP"
"1","(-6075,3725)","0","mstr_standard","I64";
;
CDS_LIB"mstr_standard"
BODY_TYPE"PLUMBING"
HDL_TAP"TRUE";
"B \NAC \NWC"6;
"S \NAC"
BN"28"113;
%"TAP"
"1","(-6075,3825)","0","mstr_standard","I65";
;
CDS_LIB"mstr_standard"
BODY_TYPE"PLUMBING"
HDL_TAP"TRUE";
"B \NAC \NWC"6;
"S \NAC"
BN"30"115;
%"TAP"
"1","(-6075,3775)","0","mstr_standard","I66";
;
CDS_LIB"mstr_standard"
BODY_TYPE"PLUMBING"
HDL_TAP"TRUE";
"B \NAC \NWC"6;
"S \NAC"
BN"29"114;
%"TAP"
"1","(-6075,3675)","0","mstr_standard","I67";
;
CDS_LIB"mstr_standard"
BODY_TYPE"PLUMBING"
HDL_TAP"TRUE";
"B \NAC \NWC"6;
"S \NAC"
BN"27"112;
%"TAP"
"1","(-6075,3625)","0","mstr_standard","I68";
;
CDS_LIB"mstr_standard"
BODY_TYPE"PLUMBING"
HDL_TAP"TRUE";
"B \NAC \NWC"6;
"S \NAC"
BN"26"111;
%"TAP"
"1","(-6075,3875)","0","mstr_standard","I69";
;
CDS_LIB"mstr_standard"
BODY_TYPE"PLUMBING"
HDL_TAP"TRUE";
"B \NAC \NWC"6;
"S \NAC"
BN"31"116;
%"VCC_CORE"
"1","(-8625,3550)","0","mstr_symbols","I7";
;
HDL_POWER"P3V3_STBY"
CDS_LIB"mstr_symbols"
VOLTAGE"3.3"
ROOM"PVCCINFAON_CPU1_CTRL";
"A"21;
%"TAP"
"1","(-6075,4025)","0","mstr_standard","I70";
;
CDS_LIB"mstr_standard"
BODY_TYPE"PLUMBING"
HDL_TAP"TRUE";
"B \NAC \NWC"5;
"S \NAC"
BN"1"118;
%"TAP"
"1","(-6075,4075)","0","mstr_standard","I71";
;
CDS_LIB"mstr_standard"
BODY_TYPE"PLUMBING"
HDL_TAP"TRUE";
"B \NAC \NWC"5;
"S \NAC"
BN"2"119;
%"TAP"
"1","(-6075,3975)","0","mstr_standard","I72";
;
CDS_LIB"mstr_standard"
BODY_TYPE"PLUMBING"
HDL_TAP"TRUE";
"B \NAC \NWC"5;
"S \NAC"
BN"0"117;
%"TAP"
"1","(-7775,4125)","2","mstr_standard","I81";
;
CDS_LIB"mstr_standard"
BODY_TYPE"PLUMBING"
HDL_TAP"TRUE";
"B \NAC \NWC"1;
"S \NAC"
BN"7"176;
%"TAP"
"1","(-7775,4825)","2","mstr_standard","I82";
;
CDS_LIB"mstr_standard"
BODY_TYPE"PLUMBING"
HDL_TAP"TRUE";
"B \NAC \NWC"2;
"S \NAC"
BN"0"172;
%"TAP"
"1","(-7775,4875)","2","mstr_standard","I83";
;
CDS_LIB"mstr_standard"
BODY_TYPE"PLUMBING"
HDL_TAP"TRUE";
"B \NAC \NWC"2;
"S \NAC"
BN"1"171;
%"TAP"
"1","(-7775,4925)","2","mstr_standard","I84";
;
CDS_LIB"mstr_standard"
BODY_TYPE"PLUMBING"
HDL_TAP"TRUE";
"B \NAC \NWC"2;
"S \NAC"
BN"2"169;
%"TAP"
"1","(-7775,4975)","2","mstr_standard","I85";
;
CDS_LIB"mstr_standard"
BODY_TYPE"PLUMBING"
HDL_TAP"TRUE";
"B \NAC \NWC"2;
"S \NAC"
BN"3"167;
%"TAP"
"1","(-7775,5075)","2","mstr_standard","I86";
;
CDS_LIB"mstr_standard"
BODY_TYPE"PLUMBING"
HDL_TAP"TRUE";
"B \NAC \NWC"2;
"S \NAC"
BN"5"164;
%"TAP"
"1","(-7775,5025)","2","mstr_standard","I87";
;
CDS_LIB"mstr_standard"
BODY_TYPE"PLUMBING"
HDL_TAP"TRUE";
"B \NAC \NWC"2;
"S \NAC"
BN"4"166;
%"TAP"
"1","(-7775,5225)","2","mstr_standard","I88";
;
CDS_LIB"mstr_standard"
BODY_TYPE"PLUMBING"
HDL_TAP"TRUE";
"B \NAC \NWC"3;
"S \NAC"
BN"0"24;
%"TAP"
"1","(-7775,5125)","2","mstr_standard","I89";
;
CDS_LIB"mstr_standard"
BODY_TYPE"PLUMBING"
HDL_TAP"TRUE";
"B \NAC \NWC"2;
"S \NAC"
BN"6"162;
%"TAP"
"1","(-7775,5275)","2","mstr_standard","I90";
;
CDS_LIB"mstr_standard"
BODY_TYPE"PLUMBING"
HDL_TAP"TRUE";
"B \NAC \NWC"3;
"S \NAC"
BN"1"71;
%"TAP"
"1","(-7775,5325)","2","mstr_standard","I91";
;
CDS_LIB"mstr_standard"
BODY_TYPE"PLUMBING"
HDL_TAP"TRUE";
"B \NAC \NWC"3;
"S \NAC"
BN"2"170;
%"TAP"
"1","(-7775,5375)","2","mstr_standard","I92";
;
CDS_LIB"mstr_standard"
BODY_TYPE"PLUMBING"
HDL_TAP"TRUE";
"B \NAC \NWC"3;
"S \NAC"
BN"3"168;
%"TAP"
"1","(-7775,5425)","2","mstr_standard","I93";
;
CDS_LIB"mstr_standard"
BODY_TYPE"PLUMBING"
HDL_TAP"TRUE";
"B \NAC \NWC"3;
"S \NAC"
BN"4"72;
%"TAP"
"1","(-7775,5475)","2","mstr_standard","I94";
;
CDS_LIB"mstr_standard"
BODY_TYPE"PLUMBING"
HDL_TAP"TRUE";
"B \NAC \NWC"3;
"S \NAC"
BN"5"165;
%"TAP"
"1","(-7775,5525)","2","mstr_standard","I95";
;
CDS_LIB"mstr_standard"
BODY_TYPE"PLUMBING"
HDL_TAP"TRUE";
"B \NAC \NWC"3;
"S \NAC"
BN"6"163;
%"TAP"
"1","(-6075,4125)","0","mstr_standard","I96";
;
CDS_LIB"mstr_standard"
BODY_TYPE"PLUMBING"
HDL_TAP"TRUE";
"B \NAC \NWC"5;
"S \NAC"
BN"3"120;
%"TAP"
"1","(-6075,4175)","0","mstr_standard","I97";
;
CDS_LIB"mstr_standard"
BODY_TYPE"PLUMBING"
HDL_TAP"TRUE";
"B \NAC \NWC"5;
"S \NAC"
BN"4"121;
%"TAP"
"1","(-6075,4225)","0","mstr_standard","I98";
;
CDS_LIB"mstr_standard"
BODY_TYPE"PLUMBING"
HDL_TAP"TRUE";
"B \NAC \NWC"5;
"S \NAC"
BN"5"122;
%"TAP"
"1","(-6075,4275)","0","mstr_standard","I99";
;
CDS_LIB"mstr_standard"
BODY_TYPE"PLUMBING"
HDL_TAP"TRUE";
"B \NAC \NWC"5;
"S \NAC"
BN"6"123;
END.
